(kicad_pcb
	(version 20260206)
	(generator "pcbnew")
	(generator_version "10.0")
	(general
		(thickness 1.6)
		(legacy_teardrops no)
	)
	(paper "A4")
	(title_block
		(title "01162023_DA0F0TEBIF0_F0T_Expander_BD_F_brd_V02_OCP.brd")
		(comment 1 "Grand Teton / footprints 5871-5877 of 9728")
	)
	(layers
		(0 "F.Cu" signal "TOP")
		(4 "In1.Cu" signal "GND")
		(6 "In2.Cu" signal "VCC")
		(8 "In3.Cu" signal "VCC1")
		(10 "In4.Cu" signal "GND1")
		(12 "In5.Cu" signal "IN1")
		(14 "In6.Cu" signal "GND2")
		(16 "In7.Cu" signal "IN2")
		(18 "In8.Cu" signal "GND3")
		(20 "In9.Cu" signal "IN3")
		(22 "In10.Cu" signal "GND4")
		(24 "In11.Cu" signal "IN4")
		(26 "In12.Cu" signal "GND5")
		(28 "In13.Cu" signal "IN5")
		(30 "In14.Cu" signal "GND6")
		(32 "In15.Cu" signal "IN6")
		(34 "In16.Cu" signal "GND7")
		(2 "B.Cu" signal "BOTTOM")
		(9 "F.Adhes" user "F.Adhesive")
		(11 "B.Adhes" user "B.Adhesive")
		(13 "F.Paste" user "Package Geometry/Pastemask Top")
		(15 "B.Paste" user "Package Geometry/Pastemask Bottom")
		(5 "F.SilkS" user "Ref Des/Silkscreen Top")
		(7 "B.SilkS" user "Ref Des/Silkscreen Bottom")
		(1 "F.Mask" user "Board Geometry/Soldermask Top")
		(3 "B.Mask" user "Board Geometry/Soldermask Bottom")
		(17 "Dwgs.User" user "User.Drawings")
		(19 "Cmts.User" user "User.Comments")
		(21 "Eco1.User" user "User.Eco1")
		(23 "Eco2.User" user "User.Eco2")
		(25 "Edge.Cuts" user "Board Geometry/Outline")
		(27 "Margin" user)
		(31 "F.CrtYd" user "Package Geometry/Place Bound Top")
		(29 "B.CrtYd" user "Package Geometry/Place Bound Bottom")
		(35 "F.Fab" user "Ref Des/Assembly Top")
		(33 "B.Fab" user "Ref Des/Assembly Bottom")
	)
	(footprint ""
		(layer "F.Cu")
		(at 336.042 -159.766 180)
		(property "Reference" "R4800"
			(at 0 0 180)
			(layer "F.SilkS")
			(hide yes)
			(effects
				(font
					(size 1.27 1.27)
				)
			)
		)
		(property "Value" ""
			(at 0 0 180)
			(layer "F.Fab")
			(effects
				(font
					(size 1.27 1.27)
				)
			)
		)
		(duplicate_pad_numbers_are_jumpers no)
		(fp_line
			(start 0.7874 0.4064)
			(end -0.7874 0.4064)
			(stroke
				(width 0.1524)
				(type default)
			)
			(layer "F.SilkS")
		)
		(fp_line
			(start 0.7874 -0.4064)
			(end 0.7874 0.4064)
			(stroke
				(width 0.1524)
				(type default)
			)
			(layer "F.SilkS")
		)
		(fp_line
			(start -0.7874 0.4064)
			(end -0.7874 -0.4064)
			(stroke
				(width 0.1524)
				(type default)
			)
			(layer "F.SilkS")
		)
		(fp_line
			(start -0.7874 -0.4064)
			(end 0.7874 -0.4064)
			(stroke
				(width 0.1524)
				(type default)
			)
			(layer "F.SilkS")
		)
		(fp_line
			(start 0.67945 0.3048)
			(end 0.120396 0.3048)
			(stroke
				(width 0.1)
				(type default)
			)
			(layer "F.Fab")
		)
		(fp_line
			(start 0.67945 -0.3048)
			(end 0.67945 0.3048)
			(stroke
				(width 0.1)
				(type default)
			)
			(layer "F.Fab")
		)
		(fp_line
			(start 0.12065 -0.2794)
			(end 0.12065 -0.3048)
			(stroke
				(width 0.1)
				(type default)
			)
			(layer "F.Fab")
		)
		(fp_line
			(start 0.12065 -0.3048)
			(end 0.67945 -0.3048)
			(stroke
				(width 0.1)
				(type default)
			)
			(layer "F.Fab")
		)
		(fp_line
			(start 0.120396 0.3048)
			(end 0.120396 0.2794)
			(stroke
				(width 0.1)
				(type default)
			)
			(layer "F.Fab")
		)
		(fp_line
			(start 0.120396 0.2794)
			(end -0.12065 0.2794)
			(stroke
				(width 0.1)
				(type default)
			)
			(layer "F.Fab")
		)
		(fp_line
			(start -0.12065 0.3048)
			(end -0.67945 0.3048)
			(stroke
				(width 0.1)
				(type default)
			)
			(layer "F.Fab")
		)
		(fp_line
			(start -0.12065 0.2794)
			(end -0.12065 0.3048)
			(stroke
				(width 0.1)
				(type default)
			)
			(layer "F.Fab")
		)
		(fp_line
			(start -0.12065 -0.2794)
			(end 0.12065 -0.2794)
			(stroke
				(width 0.1)
				(type default)
			)
			(layer "F.Fab")
		)
		(fp_line
			(start -0.12065 -0.305054)
			(end -0.12065 -0.2794)
			(stroke
				(width 0.1)
				(type default)
			)
			(layer "F.Fab")
		)
		(fp_line
			(start -0.67945 0.3048)
			(end -0.67945 -0.305054)
			(stroke
				(width 0.1)
				(type default)
			)
			(layer "F.Fab")
		)
		(fp_line
			(start -0.67945 -0.305054)
			(end -0.12065 -0.305054)
			(stroke
				(width 0.1)
				(type default)
			)
			(layer "F.Fab")
		)
		(pad "1" smd circle
			(at -0.40005 0 180)
			(size 0 0)
			(layers "F.Cu" "F.Mask" "F.Paste")
			(net "SSD12_PEX_PWR_EN_R")
		)
		(pad "2" smd circle
			(at 0.40005 0 180)
			(size 0 0)
			(layers "F.Cu" "F.Mask" "F.Paste")
			(net "GND")
		)
	)
	(footprint ""
		(layer "F.Cu")
		(at 414.676082 -200.381108 -90)
		(property "Reference" "R6433"
			(at 0 0 270)
			(layer "F.SilkS")
			(hide yes)
			(effects
				(font
					(size 1.27 1.27)
				)
			)
		)
		(property "Value" ""
			(at 0 0 270)
			(layer "F.Fab")
			(effects
				(font
					(size 1.27 1.27)
				)
			)
		)
		(duplicate_pad_numbers_are_jumpers no)
		(fp_line
			(start -0.7874 0.4064)
			(end -0.7874 -0.4064)
			(stroke
				(width 0.1524)
				(type default)
			)
			(layer "F.SilkS")
		)
		(fp_line
			(start 0.7874 0.4064)
			(end -0.7874 0.4064)
			(stroke
				(width 0.1524)
				(type default)
			)
			(layer "F.SilkS")
		)
		(fp_line
			(start -0.7874 -0.4064)
			(end 0.7874 -0.4064)
			(stroke
				(width 0.1524)
				(type default)
			)
			(layer "F.SilkS")
		)
		(fp_line
			(start 0.7874 -0.4064)
			(end 0.7874 0.4064)
			(stroke
				(width 0.1524)
				(type default)
			)
			(layer "F.SilkS")
		)
		(fp_line
			(start -0.67945 0.3048)
			(end -0.67945 -0.305054)
			(stroke
				(width 0.1)
				(type default)
			)
			(layer "F.Fab")
		)
		(fp_line
			(start -0.12065 0.3048)
			(end -0.67945 0.3048)
			(stroke
				(width 0.1)
				(type default)
			)
			(layer "F.Fab")
		)
		(fp_line
			(start 0.120396 0.3048)
			(end 0.120396 0.2794)
			(stroke
				(width 0.1)
				(type default)
			)
			(layer "F.Fab")
		)
		(fp_line
			(start 0.67945 0.3048)
			(end 0.120396 0.3048)
			(stroke
				(width 0.1)
				(type default)
			)
			(layer "F.Fab")
		)
		(fp_line
			(start -0.12065 0.2794)
			(end -0.12065 0.3048)
			(stroke
				(width 0.1)
				(type default)
			)
			(layer "F.Fab")
		)
		(fp_line
			(start 0.120396 0.2794)
			(end -0.12065 0.2794)
			(stroke
				(width 0.1)
				(type default)
			)
			(layer "F.Fab")
		)
		(fp_line
			(start -0.12065 -0.2794)
			(end 0.12065 -0.2794)
			(stroke
				(width 0.1)
				(type default)
			)
			(layer "F.Fab")
		)
		(fp_line
			(start 0.12065 -0.2794)
			(end 0.12065 -0.3048)
			(stroke
				(width 0.1)
				(type default)
			)
			(layer "F.Fab")
		)
		(fp_line
			(start 0.12065 -0.3048)
			(end 0.67945 -0.3048)
			(stroke
				(width 0.1)
				(type default)
			)
			(layer "F.Fab")
		)
		(fp_line
			(start 0.67945 -0.3048)
			(end 0.67945 0.3048)
			(stroke
				(width 0.1)
				(type default)
			)
			(layer "F.Fab")
		)
		(fp_line
			(start -0.67945 -0.305054)
			(end -0.12065 -0.305054)
			(stroke
				(width 0.1)
				(type default)
			)
			(layer "F.Fab")
		)
		(fp_line
			(start -0.12065 -0.305054)
			(end -0.12065 -0.2794)
			(stroke
				(width 0.1)
				(type default)
			)
			(layer "F.Fab")
		)
		(pad "1" smd circle
			(at -0.40005 0 270)
			(size 0 0)
			(layers "F.Cu" "F.Mask" "F.Paste")
			(net "FPGA_PEX1_MODE_SEL2_D_N")
		)
		(pad "2" smd circle
			(at 0.40005 0 270)
			(size 0 0)
			(layers "F.Cu" "F.Mask" "F.Paste")
			(net "P3V3_AUX")
		)
	)
	(footprint ""
		(layer "F.Cu")
		(at 454.542398 -235.223558 90)
		(property "Reference" "R6612"
			(at 0 0 90)
			(layer "F.SilkS")
			(hide yes)
			(effects
				(font
					(size 1.27 1.27)
				)
			)
		)
		(property "Value" ""
			(at 0 0 90)
			(layer "F.Fab")
			(effects
				(font
					(size 1.27 1.27)
				)
			)
		)
		(duplicate_pad_numbers_are_jumpers no)
		(fp_line
			(start 0.7874 -0.4064)
			(end 0.7874 0.4064)
			(stroke
				(width 0.1524)
				(type default)
			)
			(layer "F.SilkS")
		)
		(fp_line
			(start -0.7874 -0.4064)
			(end 0.7874 -0.4064)
			(stroke
				(width 0.1524)
				(type default)
			)
			(layer "F.SilkS")
		)
		(fp_line
			(start 0.7874 0.4064)
			(end -0.7874 0.4064)
			(stroke
				(width 0.1524)
				(type default)
			)
			(layer "F.SilkS")
		)
		(fp_line
			(start -0.7874 0.4064)
			(end -0.7874 -0.4064)
			(stroke
				(width 0.1524)
				(type default)
			)
			(layer "F.SilkS")
		)
		(fp_line
			(start -0.12065 -0.305054)
			(end -0.12065 -0.2794)
			(stroke
				(width 0.1)
				(type default)
			)
			(layer "F.Fab")
		)
		(fp_line
			(start -0.67945 -0.305054)
			(end -0.12065 -0.305054)
			(stroke
				(width 0.1)
				(type default)
			)
			(layer "F.Fab")
		)
		(fp_line
			(start 0.67945 -0.3048)
			(end 0.67945 0.3048)
			(stroke
				(width 0.1)
				(type default)
			)
			(layer "F.Fab")
		)
		(fp_line
			(start 0.12065 -0.3048)
			(end 0.67945 -0.3048)
			(stroke
				(width 0.1)
				(type default)
			)
			(layer "F.Fab")
		)
		(fp_line
			(start 0.12065 -0.2794)
			(end 0.12065 -0.3048)
			(stroke
				(width 0.1)
				(type default)
			)
			(layer "F.Fab")
		)
		(fp_line
			(start -0.12065 -0.2794)
			(end 0.12065 -0.2794)
			(stroke
				(width 0.1)
				(type default)
			)
			(layer "F.Fab")
		)
		(fp_line
			(start 0.120396 0.2794)
			(end -0.12065 0.2794)
			(stroke
				(width 0.1)
				(type default)
			)
			(layer "F.Fab")
		)
		(fp_line
			(start -0.12065 0.2794)
			(end -0.12065 0.3048)
			(stroke
				(width 0.1)
				(type default)
			)
			(layer "F.Fab")
		)
		(fp_line
			(start 0.67945 0.3048)
			(end 0.120396 0.3048)
			(stroke
				(width 0.1)
				(type default)
			)
			(layer "F.Fab")
		)
		(fp_line
			(start 0.120396 0.3048)
			(end 0.120396 0.2794)
			(stroke
				(width 0.1)
				(type default)
			)
			(layer "F.Fab")
		)
		(fp_line
			(start -0.12065 0.3048)
			(end -0.67945 0.3048)
			(stroke
				(width 0.1)
				(type default)
			)
			(layer "F.Fab")
		)
		(fp_line
			(start -0.67945 0.3048)
			(end -0.67945 -0.305054)
			(stroke
				(width 0.1)
				(type default)
			)
			(layer "F.Fab")
		)
		(pad "1" smd circle
			(at -0.40005 0 90)
			(size 0 0)
			(layers "F.Cu" "F.Mask" "F.Paste")
			(net "UART_PEX0_SDB_CP2108_RX")
		)
		(pad "2" smd circle
			(at 0.40005 0 90)
			(size 0 0)
			(layers "F.Cu" "F.Mask" "F.Paste")
			(net "UART_PEX0_SDB_R_RX")
		)
	)
	(footprint ""
		(layer "F.Cu")
		(at 11.912854 -45.111924 180)
		(property "Reference" "R5540"
			(at 0 0 180)
			(layer "F.SilkS")
			(hide yes)
			(effects
				(font
					(size 1.27 1.27)
				)
			)
		)
		(property "Value" ""
			(at 0 0 180)
			(layer "F.Fab")
			(effects
				(font
					(size 1.27 1.27)
				)
			)
		)
		(duplicate_pad_numbers_are_jumpers no)
		(fp_line
			(start 0.7874 0.4064)
			(end -0.7874 0.4064)
			(stroke
				(width 0.1524)
				(type default)
			)
			(layer "F.SilkS")
		)
		(fp_line
			(start 0.7874 -0.4064)
			(end 0.7874 0.4064)
			(stroke
				(width 0.1524)
				(type default)
			)
			(layer "F.SilkS")
		)
		(fp_line
			(start -0.7874 0.4064)
			(end -0.7874 -0.4064)
			(stroke
				(width 0.1524)
				(type default)
			)
			(layer "F.SilkS")
		)
		(fp_line
			(start -0.7874 -0.4064)
			(end 0.7874 -0.4064)
			(stroke
				(width 0.1524)
				(type default)
			)
			(layer "F.SilkS")
		)
		(fp_line
			(start 0.67945 0.3048)
			(end 0.120396 0.3048)
			(stroke
				(width 0.1)
				(type default)
			)
			(layer "F.Fab")
		)
		(fp_line
			(start 0.67945 -0.3048)
			(end 0.67945 0.3048)
			(stroke
				(width 0.1)
				(type default)
			)
			(layer "F.Fab")
		)
		(fp_line
			(start 0.12065 -0.2794)
			(end 0.12065 -0.3048)
			(stroke
				(width 0.1)
				(type default)
			)
			(layer "F.Fab")
		)
		(fp_line
			(start 0.12065 -0.3048)
			(end 0.67945 -0.3048)
			(stroke
				(width 0.1)
				(type default)
			)
			(layer "F.Fab")
		)
		(fp_line
			(start 0.120396 0.3048)
			(end 0.120396 0.2794)
			(stroke
				(width 0.1)
				(type default)
			)
			(layer "F.Fab")
		)
		(fp_line
			(start 0.120396 0.2794)
			(end -0.12065 0.2794)
			(stroke
				(width 0.1)
				(type default)
			)
			(layer "F.Fab")
		)
		(fp_line
			(start -0.12065 0.3048)
			(end -0.67945 0.3048)
			(stroke
				(width 0.1)
				(type default)
			)
			(layer "F.Fab")
		)
		(fp_line
			(start -0.12065 0.2794)
			(end -0.12065 0.3048)
			(stroke
				(width 0.1)
				(type default)
			)
			(layer "F.Fab")
		)
		(fp_line
			(start -0.12065 -0.2794)
			(end 0.12065 -0.2794)
			(stroke
				(width 0.1)
				(type default)
			)
			(layer "F.Fab")
		)
		(fp_line
			(start -0.12065 -0.305054)
			(end -0.12065 -0.2794)
			(stroke
				(width 0.1)
				(type default)
			)
			(layer "F.Fab")
		)
		(fp_line
			(start -0.67945 0.3048)
			(end -0.67945 -0.305054)
			(stroke
				(width 0.1)
				(type default)
			)
			(layer "F.Fab")
		)
		(fp_line
			(start -0.67945 -0.305054)
			(end -0.12065 -0.305054)
			(stroke
				(width 0.1)
				(type default)
			)
			(layer "F.Fab")
		)
		(pad "1" smd circle
			(at -0.40005 0 180)
			(size 0 0)
			(layers "F.Cu" "F.Mask" "F.Paste")
			(net "P3V3_AUX")
		)
		(pad "2" smd circle
			(at 0.40005 0 180)
			(size 0 0)
			(layers "F.Cu" "F.Mask" "F.Paste")
			(net "SSD0_AUX_P3V3_EN")
		)
	)
	(footprint ""
		(layer "F.Cu")
		(at 163.985702 -25.1587 -90)
		(property "Reference" "R5742"
			(at 0 0 270)
			(layer "F.SilkS")
			(hide yes)
			(effects
				(font
					(size 1.27 1.27)
				)
			)
		)
		(property "Value" ""
			(at 0 0 270)
			(layer "F.Fab")
			(effects
				(font
					(size 1.27 1.27)
				)
			)
		)
		(duplicate_pad_numbers_are_jumpers no)
		(fp_line
			(start -0.7874 0.4064)
			(end -0.7874 -0.4064)
			(stroke
				(width 0.1524)
				(type default)
			)
			(layer "F.SilkS")
		)
		(fp_line
			(start 0.7874 0.4064)
			(end -0.7874 0.4064)
			(stroke
				(width 0.1524)
				(type default)
			)
			(layer "F.SilkS")
		)
		(fp_line
			(start -0.7874 -0.4064)
			(end 0.7874 -0.4064)
			(stroke
				(width 0.1524)
				(type default)
			)
			(layer "F.SilkS")
		)
		(fp_line
			(start 0.7874 -0.4064)
			(end 0.7874 0.4064)
			(stroke
				(width 0.1524)
				(type default)
			)
			(layer "F.SilkS")
		)
		(fp_line
			(start -0.67945 0.3048)
			(end -0.67945 -0.305054)
			(stroke
				(width 0.1)
				(type default)
			)
			(layer "F.Fab")
		)
		(fp_line
			(start -0.12065 0.3048)
			(end -0.67945 0.3048)
			(stroke
				(width 0.1)
				(type default)
			)
			(layer "F.Fab")
		)
		(fp_line
			(start 0.120396 0.3048)
			(end 0.120396 0.2794)
			(stroke
				(width 0.1)
				(type default)
			)
			(layer "F.Fab")
		)
		(fp_line
			(start 0.67945 0.3048)
			(end 0.120396 0.3048)
			(stroke
				(width 0.1)
				(type default)
			)
			(layer "F.Fab")
		)
		(fp_line
			(start -0.12065 0.2794)
			(end -0.12065 0.3048)
			(stroke
				(width 0.1)
				(type default)
			)
			(layer "F.Fab")
		)
		(fp_line
			(start 0.120396 0.2794)
			(end -0.12065 0.2794)
			(stroke
				(width 0.1)
				(type default)
			)
			(layer "F.Fab")
		)
		(fp_line
			(start -0.12065 -0.2794)
			(end 0.12065 -0.2794)
			(stroke
				(width 0.1)
				(type default)
			)
			(layer "F.Fab")
		)
		(fp_line
			(start 0.12065 -0.2794)
			(end 0.12065 -0.3048)
			(stroke
				(width 0.1)
				(type default)
			)
			(layer "F.Fab")
		)
		(fp_line
			(start 0.12065 -0.3048)
			(end 0.67945 -0.3048)
			(stroke
				(width 0.1)
				(type default)
			)
			(layer "F.Fab")
		)
		(fp_line
			(start 0.67945 -0.3048)
			(end 0.67945 0.3048)
			(stroke
				(width 0.1)
				(type default)
			)
			(layer "F.Fab")
		)
		(fp_line
			(start -0.67945 -0.305054)
			(end -0.12065 -0.305054)
			(stroke
				(width 0.1)
				(type default)
			)
			(layer "F.Fab")
		)
		(fp_line
			(start -0.12065 -0.305054)
			(end -0.12065 -0.2794)
			(stroke
				(width 0.1)
				(type default)
			)
			(layer "F.Fab")
		)
		(pad "1" smd circle
			(at -0.40005 0 270)
			(size 0 0)
			(layers "F.Cu" "F.Mask" "F.Paste")
			(net "SSD5_LED_ISO_N")
		)
		(pad "2" smd circle
			(at 0.40005 0 270)
			(size 0 0)
			(layers "F.Cu" "F.Mask" "F.Paste")
			(net "SSD5_LED_ISO_R_N")
		)
	)
	(footprint ""
		(layer "F.Cu")
		(at 37.960808 -356.244906 90)
		(property "Reference" "C2170"
			(at 0 0 90)
			(layer "F.SilkS")
			(hide yes)
			(effects
				(font
					(size 1.27 1.27)
				)
			)
		)
		(property "Value" ""
			(at 0 0 90)
			(layer "F.Fab")
			(effects
				(font
					(size 1.27 1.27)
				)
			)
		)
		(duplicate_pad_numbers_are_jumpers no)
		(fp_line
			(start 0.299974 -0.150114)
			(end 0.299974 0.150114)
			(stroke
				(width 0.1)
				(type default)
			)
			(layer "F.Fab")
		)
		(fp_line
			(start -0.299974 -0.150114)
			(end 0.299974 -0.150114)
			(stroke
				(width 0.1)
				(type default)
			)
			(layer "F.Fab")
		)
		(fp_line
			(start 0.299974 0.150114)
			(end -0.299974 0.150114)
			(stroke
				(width 0.1)
				(type default)
			)
			(layer "F.Fab")
		)
		(fp_line
			(start -0.299974 0.150114)
			(end -0.299974 -0.150114)
			(stroke
				(width 0.1)
				(type default)
			)
			(layer "F.Fab")
		)
		(pad "1" smd rect
			(at -0.2667 0 90)
			(size 0.3048 0.381)
			(layers "F.Cu" "F.Mask" "F.Paste")
			(net "P5E_PEX0_STN4_TX_DP<70>")
		)
		(pad "2" smd rect
			(at 0.2667 0 90)
			(size 0.3048 0.381)
			(layers "F.Cu" "F.Mask" "F.Paste")
			(net "P5E_PEX0_STN4_TX_C_DP<70>")
		)
	)
	(footprint ""
		(layer "F.Cu")
		(at 97.471484 -25.342342 -90)
		(property "Reference" "R418"
			(at 0 0 270)
			(layer "F.SilkS")
			(hide yes)
			(effects
				(font
					(size 1.27 1.27)
				)
			)
		)
		(property "Value" ""
			(at 0 0 270)
			(layer "F.Fab")
			(effects
				(font
					(size 1.27 1.27)
				)
			)
		)
		(duplicate_pad_numbers_are_jumpers no)
		(fp_line
			(start -0.7874 0.4064)
			(end -0.7874 -0.4064)
			(stroke
				(width 0.1524)
				(type default)
			)
			(layer "F.SilkS")
		)
		(fp_line
			(start 0.7874 0.4064)
			(end -0.7874 0.4064)
			(stroke
				(width 0.1524)
				(type default)
			)
			(layer "F.SilkS")
		)
		(fp_line
			(start -0.7874 -0.4064)
			(end 0.7874 -0.4064)
			(stroke
				(width 0.1524)
				(type default)
			)
			(layer "F.SilkS")
		)
		(fp_line
			(start 0.7874 -0.4064)
			(end 0.7874 0.4064)
			(stroke
				(width 0.1524)
				(type default)
			)
			(layer "F.SilkS")
		)
		(fp_line
			(start -0.67945 0.3048)
			(end -0.67945 -0.305054)
			(stroke
				(width 0.1)
				(type default)
			)
			(layer "F.Fab")
		)
		(fp_line
			(start -0.12065 0.3048)
			(end -0.67945 0.3048)
			(stroke
				(width 0.1)
				(type default)
			)
			(layer "F.Fab")
		)
		(fp_line
			(start 0.120396 0.3048)
			(end 0.120396 0.2794)
			(stroke
				(width 0.1)
				(type default)
			)
			(layer "F.Fab")
		)
		(fp_line
			(start 0.67945 0.3048)
			(end 0.120396 0.3048)
			(stroke
				(width 0.1)
				(type default)
			)
			(layer "F.Fab")
		)
		(fp_line
			(start -0.12065 0.2794)
			(end -0.12065 0.3048)
			(stroke
				(width 0.1)
				(type default)
			)
			(layer "F.Fab")
		)
		(fp_line
			(start 0.120396 0.2794)
			(end -0.12065 0.2794)
			(stroke
				(width 0.1)
				(type default)
			)
			(layer "F.Fab")
		)
		(fp_line
			(start -0.12065 -0.2794)
			(end 0.12065 -0.2794)
			(stroke
				(width 0.1)
				(type default)
			)
			(layer "F.Fab")
		)
		(fp_line
			(start 0.12065 -0.2794)
			(end 0.12065 -0.3048)
			(stroke
				(width 0.1)
				(type default)
			)
			(layer "F.Fab")
		)
		(fp_line
			(start 0.12065 -0.3048)
			(end 0.67945 -0.3048)
			(stroke
				(width 0.1)
				(type default)
			)
			(layer "F.Fab")
		)
		(fp_line
			(start 0.67945 -0.3048)
			(end 0.67945 0.3048)
			(stroke
				(width 0.1)
				(type default)
			)
			(layer "F.Fab")
		)
		(fp_line
			(start -0.67945 -0.305054)
			(end -0.12065 -0.305054)
			(stroke
				(width 0.1)
				(type default)
			)
			(layer "F.Fab")
		)
		(fp_line
			(start -0.12065 -0.305054)
			(end -0.12065 -0.2794)
			(stroke
				(width 0.1)
				(type default)
			)
			(layer "F.Fab")
		)
		(pad "1" smd circle
			(at -0.40005 0 270)
			(size 0 0)
			(layers "F.Cu" "F.Mask" "F.Paste")
			(net "P3V3_SSD3")
		)
		(pad "2" smd circle
			(at 0.40005 0 270)
			(size 0 0)
			(layers "F.Cu" "F.Mask" "F.Paste")
			(net "DUALPORT_N_SSD3")
		)
	)
)
